# S9S_MB_2U (Grand Teton) — schematic netlist excerpt (pin names and nets, part order shuffled) for the footprints in the layout excerpt that follows; sources: Cadence DE-HDL packaged netlist, KiCad conversion of 03242023_DA0F0TMBIJ0_F0T_Motherboard_J_brd_V01_OCP.brd

R566  Q_RES  22 1% CHIP  pkg 0402LF  page 209 : A = CLK_100M_OCP_SFF_1_R_DN ; B = CLK_100M_OCP_SFF_1_DN

(kicad_pcb
	(version 20260206)
	(generator "pcbnew")
	(generator_version "10.0")
	(general
		(thickness 1.6)
		(legacy_teardrops no)
	)
	(paper "A4")
	(title_block
		(title "03242023_DA0F0TMBIJ0_F0T_Motherboard_J_brd_V01_OCP.brd")
		(comment 1 "Grand Teton / footprints 3210-3210 of 6105")
	)
	(layers
		(0 "F.Cu" signal "TOP")
		(4 "In1.Cu" signal "GND")
		(6 "In2.Cu" signal "IN1")
		(8 "In3.Cu" signal "GND1")
		(10 "In4.Cu" signal "IN2")
		(12 "In5.Cu" signal "GND2")
		(14 "In6.Cu" signal "IN3")
		(16 "In7.Cu" signal "GND3")
		(18 "In8.Cu" signal "VCC")
		(20 "In9.Cu" signal "VCC1")
		(22 "In10.Cu" signal "GND4")
		(24 "In11.Cu" signal "IN4")
		(26 "In12.Cu" signal "GND5")
		(28 "In13.Cu" signal "IN5")
		(30 "In14.Cu" signal "GND6")
		(32 "In15.Cu" signal "IN6")
		(34 "In16.Cu" signal "GND7")
		(2 "B.Cu" signal "BOTTOM")
		(9 "F.Adhes" user "F.Adhesive")
		(11 "B.Adhes" user "B.Adhesive")
		(13 "F.Paste" user "Package Geometry/Pastemask Top")
		(15 "B.Paste" user "Package Geometry/Pastemask Bottom")
		(5 "F.SilkS" user "Ref Des/Silkscreen Top")
		(7 "B.SilkS" user "Ref Des/Silkscreen Bottom")
		(1 "F.Mask" user "Board Geometry/Soldermask Top")
		(3 "B.Mask" user "Board Geometry/Soldermask Bottom")
		(17 "Dwgs.User" user "User.Drawings")
		(19 "Cmts.User" user "User.Comments")
		(21 "Eco1.User" user "User.Eco1")
		(23 "Eco2.User" user "User.Eco2")
		(25 "Edge.Cuts" user "Board Geometry/Outline")
		(27 "Margin" user)
		(31 "F.CrtYd" user "Package Geometry/Place Bound Top")
		(29 "B.CrtYd" user "Package Geometry/Place Bound Bottom")
		(35 "F.Fab" user "Ref Des/Assembly Top")
		(33 "B.Fab" user "Ref Des/Assembly Bottom")
	)
	(footprint ""
		(layer "F.Cu")
		(at 228.764592 -124.281946 180)
		(property "Reference" "R566"
			(at 0 0 180)
			(layer "F.SilkS")
			(hide yes)
			(effects
				(font
					(size 1.27 1.27)
				)
			)
		)
		(property "Value" ""
			(at 0 0 180)
			(layer "F.Fab")
			(effects
				(font
					(size 1.27 1.27)
				)
			)
		)
		(duplicate_pad_numbers_are_jumpers no)
		(fp_line
			(start 0.7874 -0.4064)
			(end 0.7874 0.089154)
			(stroke
				(width 0.1524)
				(type default)
			)
			(layer "F.SilkS")
		)
		(fp_line
			(start 0.520192 0.4064)
			(end -0.429768 0.4064)
			(stroke
				(width 0.1524)
				(type default)
			)
			(layer "F.SilkS")
		)
		(fp_line
			(start -0.7874 0.063754)
			(end -0.7874 -0.4064)
			(stroke
				(width 0.1524)
				(type default)
			)
			(layer "F.SilkS")
		)
		(fp_line
			(start -0.7874 -0.4064)
			(end 0.7874 -0.4064)
			(stroke
				(width 0.1524)
				(type default)
			)
			(layer "F.SilkS")
		)
		(fp_line
			(start 0.67945 0.3048)
			(end 0.120396 0.3048)
			(stroke
				(width 0.1)
				(type default)
			)
			(layer "F.Fab")
		)
		(fp_line
			(start 0.67945 -0.3048)
			(end 0.67945 0.3048)
			(stroke
				(width 0.1)
				(type default)
			)
			(layer "F.Fab")
		)
		(fp_line
			(start 0.12065 -0.2794)
			(end 0.12065 -0.3048)
			(stroke
				(width 0.1)
				(type default)
			)
			(layer "F.Fab")
		)
		(fp_line
			(start 0.12065 -0.3048)
			(end 0.67945 -0.3048)
			(stroke
				(width 0.1)
				(type default)
			)
			(layer "F.Fab")
		)
		(fp_line
			(start 0.120396 0.3048)
			(end 0.120396 0.2794)
			(stroke
				(width 0.1)
				(type default)
			)
			(layer "F.Fab")
		)
		(fp_line
			(start 0.120396 0.2794)
			(end -0.12065 0.2794)
			(stroke
				(width 0.1)
				(type default)
			)
			(layer "F.Fab")
		)
		(fp_line
			(start -0.12065 0.3048)
			(end -0.67945 0.3048)
			(stroke
				(width 0.1)
				(type default)
			)
			(layer "F.Fab")
		)
		(fp_line
			(start -0.12065 0.2794)
			(end -0.12065 0.3048)
			(stroke
				(width 0.1)
				(type default)
			)
			(layer "F.Fab")
		)
		(fp_line
			(start -0.12065 -0.2794)
			(end 0.12065 -0.2794)
			(stroke
				(width 0.1)
				(type default)
			)
			(layer "F.Fab")
		)
		(fp_line
			(start -0.12065 -0.305054)
			(end -0.12065 -0.2794)
			(stroke
				(width 0.1)
				(type default)
			)
			(layer "F.Fab")
		)
		(fp_line
			(start -0.67945 0.3048)
			(end -0.67945 -0.305054)
			(stroke
				(width 0.1)
				(type default)
			)
			(layer "F.Fab")
		)
		(fp_line
			(start -0.67945 -0.305054)
			(end -0.12065 -0.305054)
			(stroke
				(width 0.1)
				(type default)
			)
			(layer "F.Fab")
		)
		(pad "1" smd circle
			(at -0.40005 0 180)
			(size 0 0)
			(layers "F.Cu" "F.Mask" "F.Paste")
			(net "CLK_100M_OCP_SFF_1_R_DN")
		)
		(pad "2" smd circle
			(at 0.40005 0 180)
			(size 0 0)
			(layers "F.Cu" "F.Mask" "F.Paste")
			(net "CLK_100M_OCP_SFF_1_DN")
		)
	)
)
